# S9S_MB_2U (Grand Teton) — schematic netlist excerpt (pin names and nets, part order shuffled) for the footprints in the layout excerpt that follows; sources: Cadence DE-HDL packaged netlist, KiCad conversion of 03242023_DA0F0TMBIJ0_F0T_Motherboard_J_brd_V01_OCP.brd

R4201  Q_RES  1K 1% CHIP  pkg 0402LF  page 170 : A = U273_3_ADD0 ; B = GND
C445  Q_CAP  22UF 4V 20% X6S  pkg C0402  page 77 : A = PVCCFA_EHV_CPU1 ; B = GND

(kicad_pcb
	(version 20260206)
	(generator "pcbnew")
	(generator_version "10.0")
	(general
		(thickness 1.6)
		(legacy_teardrops no)
	)
	(paper "A4")
	(title_block
		(title "03242023_DA0F0TMBIJ0_F0T_Motherboard_J_brd_V01_OCP.brd")
		(comment 1 "Grand Teton / footprints 2441-2442 of 6105")
	)
	(layers
		(0 "F.Cu" signal "TOP")
		(4 "In1.Cu" signal "GND")
		(6 "In2.Cu" signal "IN1")
		(8 "In3.Cu" signal "GND1")
		(10 "In4.Cu" signal "IN2")
		(12 "In5.Cu" signal "GND2")
		(14 "In6.Cu" signal "IN3")
		(16 "In7.Cu" signal "GND3")
		(18 "In8.Cu" signal "VCC")
		(20 "In9.Cu" signal "VCC1")
		(22 "In10.Cu" signal "GND4")
		(24 "In11.Cu" signal "IN4")
		(26 "In12.Cu" signal "GND5")
		(28 "In13.Cu" signal "IN5")
		(30 "In14.Cu" signal "GND6")
		(32 "In15.Cu" signal "IN6")
		(34 "In16.Cu" signal "GND7")
		(2 "B.Cu" signal "BOTTOM")
		(9 "F.Adhes" user "F.Adhesive")
		(11 "B.Adhes" user "B.Adhesive")
		(13 "F.Paste" user "Package Geometry/Pastemask Top")
		(15 "B.Paste" user "Package Geometry/Pastemask Bottom")
		(5 "F.SilkS" user "Ref Des/Silkscreen Top")
		(7 "B.SilkS" user "Ref Des/Silkscreen Bottom")
		(1 "F.Mask" user "Board Geometry/Soldermask Top")
		(3 "B.Mask" user "Board Geometry/Soldermask Bottom")
		(17 "Dwgs.User" user "User.Drawings")
		(19 "Cmts.User" user "User.Comments")
		(21 "Eco1.User" user "User.Eco1")
		(23 "Eco2.User" user "User.Eco2")
		(25 "Edge.Cuts" user "Board Geometry/Outline")
		(27 "Margin" user)
		(31 "F.CrtYd" user "Package Geometry/Place Bound Top")
		(29 "B.CrtYd" user "Package Geometry/Place Bound Bottom")
		(35 "F.Fab" user "Ref Des/Assembly Top")
		(33 "B.Fab" user "Ref Des/Assembly Bottom")
	)
	(footprint ""
		(layer "F.Cu")
		(at 105.2957 -256.6543 -90)
		(property "Reference" "C445"
			(at 0 0 270)
			(layer "F.SilkS")
			(hide yes)
			(effects
				(font
					(size 1.27 1.27)
				)
			)
		)
		(property "Value" ""
			(at 0 0 270)
			(layer "F.Fab")
			(effects
				(font
					(size 1.27 1.27)
				)
			)
		)
		(duplicate_pad_numbers_are_jumpers no)
		(fp_line
			(start -0.7874 0.4064)
			(end -0.7874 -0.4064)
			(stroke
				(width 0.1524)
				(type default)
			)
			(layer "F.SilkS")
		)
		(fp_line
			(start 0.7874 0.4064)
			(end -0.7874 0.4064)
			(stroke
				(width 0.1524)
				(type default)
			)
			(layer "F.SilkS")
		)
		(fp_line
			(start -0.7874 -0.4064)
			(end 0.7874 -0.4064)
			(stroke
				(width 0.1524)
				(type default)
			)
			(layer "F.SilkS")
		)
		(fp_line
			(start 0.7874 -0.4064)
			(end 0.7874 0.4064)
			(stroke
				(width 0.1524)
				(type default)
			)
			(layer "F.SilkS")
		)
		(fp_line
			(start -0.67945 0.3048)
			(end -0.67945 -0.305054)
			(stroke
				(width 0.1)
				(type default)
			)
			(layer "F.Fab")
		)
		(fp_line
			(start -0.12065 0.3048)
			(end -0.67945 0.3048)
			(stroke
				(width 0.1)
				(type default)
			)
			(layer "F.Fab")
		)
		(fp_line
			(start 0.120396 0.3048)
			(end 0.120396 0.2794)
			(stroke
				(width 0.1)
				(type default)
			)
			(layer "F.Fab")
		)
		(fp_line
			(start 0.67945 0.3048)
			(end 0.120396 0.3048)
			(stroke
				(width 0.1)
				(type default)
			)
			(layer "F.Fab")
		)
		(fp_line
			(start -0.12065 0.2794)
			(end -0.12065 0.3048)
			(stroke
				(width 0.1)
				(type default)
			)
			(layer "F.Fab")
		)
		(fp_line
			(start 0.120396 0.2794)
			(end -0.12065 0.2794)
			(stroke
				(width 0.1)
				(type default)
			)
			(layer "F.Fab")
		)
		(fp_line
			(start -0.12065 -0.2794)
			(end 0.12065 -0.2794)
			(stroke
				(width 0.1)
				(type default)
			)
			(layer "F.Fab")
		)
		(fp_line
			(start 0.12065 -0.2794)
			(end 0.12065 -0.3048)
			(stroke
				(width 0.1)
				(type default)
			)
			(layer "F.Fab")
		)
		(fp_line
			(start 0.12065 -0.3048)
			(end 0.67945 -0.3048)
			(stroke
				(width 0.1)
				(type default)
			)
			(layer "F.Fab")
		)
		(fp_line
			(start 0.67945 -0.3048)
			(end 0.67945 0.3048)
			(stroke
				(width 0.1)
				(type default)
			)
			(layer "F.Fab")
		)
		(fp_line
			(start -0.67945 -0.305054)
			(end -0.12065 -0.305054)
			(stroke
				(width 0.1)
				(type default)
			)
			(layer "F.Fab")
		)
		(fp_line
			(start -0.12065 -0.305054)
			(end -0.12065 -0.2794)
			(stroke
				(width 0.1)
				(type default)
			)
			(layer "F.Fab")
		)
		(pad "1" smd circle
			(at -0.40005 0 270)
			(size 0 0)
			(layers "F.Cu" "F.Mask" "F.Paste")
			(net "PVCCFA_EHV_CPU1")
		)
		(pad "2" smd circle
			(at 0.40005 0 270)
			(size 0 0)
			(layers "F.Cu" "F.Mask" "F.Paste")
			(net "GND")
		)
	)
	(footprint ""
		(layer "F.Cu")
		(at 120.333262 -16.91005)
		(property "Reference" "R4201"
			(at 0 0 0)
			(layer "F.SilkS")
			(hide yes)
			(effects
				(font
					(size 1.27 1.27)
				)
			)
		)
		(property "Value" ""
			(at 0 0 0)
			(layer "F.Fab")
			(effects
				(font
					(size 1.27 1.27)
				)
			)
		)
		(duplicate_pad_numbers_are_jumpers no)
		(fp_line
			(start -0.7874 -0.4064)
			(end 0.7874 -0.4064)
			(stroke
				(width 0.1524)
				(type default)
			)
			(layer "F.SilkS")
		)
		(fp_line
			(start -0.7874 0.4064)
			(end -0.7874 -0.4064)
			(stroke
				(width 0.1524)
				(type default)
			)
			(layer "F.SilkS")
		)
		(fp_line
			(start 0.7874 -0.4064)
			(end 0.7874 0.4064)
			(stroke
				(width 0.1524)
				(type default)
			)
			(layer "F.SilkS")
		)
		(fp_line
			(start 0.7874 0.4064)
			(end -0.7874 0.4064)
			(stroke
				(width 0.1524)
				(type default)
			)
			(layer "F.SilkS")
		)
		(fp_line
			(start -0.67945 -0.305054)
			(end -0.12065 -0.305054)
			(stroke
				(width 0.1)
				(type default)
			)
			(layer "F.Fab")
		)
		(fp_line
			(start -0.67945 0.3048)
			(end -0.67945 -0.305054)
			(stroke
				(width 0.1)
				(type default)
			)
			(layer "F.Fab")
		)
		(fp_line
			(start -0.12065 -0.305054)
			(end -0.12065 -0.2794)
			(stroke
				(width 0.1)
				(type default)
			)
			(layer "F.Fab")
		)
		(fp_line
			(start -0.12065 -0.2794)
			(end 0.12065 -0.2794)
			(stroke
				(width 0.1)
				(type default)
			)
			(layer "F.Fab")
		)
		(fp_line
			(start -0.12065 0.2794)
			(end -0.12065 0.3048)
			(stroke
				(width 0.1)
				(type default)
			)
			(layer "F.Fab")
		)
		(fp_line
			(start -0.12065 0.3048)
			(end -0.67945 0.3048)
			(stroke
				(width 0.1)
				(type default)
			)
			(layer "F.Fab")
		)
		(fp_line
			(start 0.120396 0.2794)
			(end -0.12065 0.2794)
			(stroke
				(width 0.1)
				(type default)
			)
			(layer "F.Fab")
		)
		(fp_line
			(start 0.120396 0.3048)
			(end 0.120396 0.2794)
			(stroke
				(width 0.1)
				(type default)
			)
			(layer "F.Fab")
		)
		(fp_line
			(start 0.12065 -0.3048)
			(end 0.67945 -0.3048)
			(stroke
				(width 0.1)
				(type default)
			)
			(layer "F.Fab")
		)
		(fp_line
			(start 0.12065 -0.2794)
			(end 0.12065 -0.3048)
			(stroke
				(width 0.1)
				(type default)
			)
			(layer "F.Fab")
		)
		(fp_line
			(start 0.67945 -0.3048)
			(end 0.67945 0.3048)
			(stroke
				(width 0.1)
				(type default)
			)
			(layer "F.Fab")
		)
		(fp_line
			(start 0.67945 0.3048)
			(end 0.120396 0.3048)
			(stroke
				(width 0.1)
				(type default)
			)
			(layer "F.Fab")
		)
		(pad "1" smd circle
			(at -0.40005 0)
			(size 0 0)
			(layers "F.Cu" "F.Mask" "F.Paste")
			(net "U273_3_ADD0")
		)
		(pad "2" smd circle
			(at 0.40005 0)
			(size 0 0)
			(layers "F.Cu" "F.Mask" "F.Paste")
			(net "GND")
		)
	)
)
